# scalenode-cm4-baseboard — KiCad project settings (.kicad_pro: net classes, design rules, text variables)
{
  "board": {
    "3dviewports": [],
    "design_settings": {
      "defaults": {
        "board_outline_line_width": 0.09999999999999999,
        "copper_line_width": 0.19999999999999998,
        "copper_text_italic": false,
        "copper_text_size_h": 1.5,
        "copper_text_size_v": 1.5,
        "copper_text_thickness": 0.3,
        "copper_text_upright": false,
        "courtyard_line_width": 0.049999999999999996,
        "dimension_precision": 4,
        "dimension_units": 3,
        "dimensions": {
          "arrow_length": 1270000,
          "extension_offset": 500000,
          "keep_text_aligned": true,
          "suppress_zeroes": false,
          "text_position": 0,
          "units_format": 1
        },
        "fab_line_width": 0.09999999999999999,
        "fab_text_italic": false,
        "fab_text_size_h": 1.0,
        "fab_text_size_v": 1.0,
        "fab_text_thickness": 0.15,
        "fab_text_upright": false,
        "other_line_width": 0.09999999999999999,
        "other_text_italic": false,
        "other_text_size_h": 1.0,
        "other_text_size_v": 1.0,
        "other_text_thickness": 0.15,
        "other_text_upright": false,
        "pads": {
          "drill": 0.0,
          "height": 2.75,
          "width": 1.2
        },
        "silk_line_width": 0.15,
        "silk_text_italic": false,
        "silk_text_size_h": 1.0,
        "silk_text_size_v": 1.0,
        "silk_text_thickness": 0.15,
        "silk_text_upright": false,
        "zones": {
          "45_degree_only": false,
          "min_clearance": 0.254
        }
      },
      "diff_pair_dimensions": [
        {
          "gap": 0.0,
          "via_gap": 0.0,
          "width": 0.0
        }
      ],
      "drc_exclusions": [],
      "meta": {
        "filename": "board_design_settings.json",
        "version": 2
      },
      "rule_severities": {
        "annular_width": "error",
        "clearance": "error",
        "connection_width": "warning",
        "copper_edge_clearance": "error",
        "copper_sliver": "warning",
        "courtyards_overlap": "error",
        "diff_pair_gap_out_of_range": "error",
        "diff_pair_uncoupled_length_too_long": "error",
        "drill_out_of_range": "error",
        "duplicate_footprints": "warning",
        "extra_footprint": "warning",
        "footprint": "error",
        "footprint_type_mismatch": "error",
        "hole_clearance": "error",
        "hole_near_hole": "error",
        "invalid_outline": "error",
        "isolated_copper": "warning",
        "item_on_disabled_layer": "error",
        "items_not_allowed": "error",
        "length_out_of_range": "error",
        "lib_footprint_issues": "warning",
        "lib_footprint_mismatch": "ignore",
        "malformed_courtyard": "error",
        "microvia_drill_out_of_range": "error",
        "missing_courtyard": "ignore",
        "missing_footprint": "warning",
        "net_conflict": "warning",
        "npth_inside_courtyard": "ignore",
        "padstack": "error",
        "pth_inside_courtyard": "ignore",
        "shorting_items": "error",
        "silk_edge_clearance": "warning",
        "silk_over_copper": "ignore",
        "silk_overlap": "ignore",
        "skew_out_of_range": "error",
        "solder_mask_bridge": "ignore",
        "starved_thermal": "error",
        "text_height": "warning",
        "text_thickness": "warning",
        "through_hole_pad_without_hole": "error",
        "too_many_vias": "error",
        "track_dangling": "warning",
        "track_width": "error",
        "tracks_crossing": "error",
        "unconnected_items": "error",
        "unresolved_variable": "error",
        "via_dangling": "warning",
        "zones_intersect": "error"
      },
      "rule_severitieslegacy_courtyards_overlap": true,
      "rule_severitieslegacy_no_courtyard_defined": false,
      "rules": {
        "allow_blind_buried_vias": false,
        "allow_microvias": false,
        "max_error": 0.005,
        "min_clearance": 0.125,
        "min_connection": 0.0,
        "min_copper_edge_clearance": 0.19999999999999998,
        "min_hole_clearance": 0.19999999999999998,
        "min_hole_to_hole": 0.25,
        "min_microvia_diameter": 0.19999999999999998,
        "min_microvia_drill": 0.09999999999999999,
        "min_resolved_spokes": 2,
        "min_silk_clearance": 0.0,
        "min_text_height": 0.7,
        "min_text_thickness": 0.08,
        "min_through_hole_diameter": 0.15,
        "min_track_width": 0.125,
        "min_via_annular_width": 0.125,
        "min_via_diameter": 0.44999999999999996,
        "solder_mask_to_copper_clearance": 0.0,
        "use_height_for_length_calcs": true
      },
      "teardrop_options": [
        {
          "td_allow_use_two_tracks": true,
          "td_curve_segcount": 5,
          "td_on_pad_in_zone": false,
          "td_onpadsmd": true,
          "td_onroundshapesonly": false,
          "td_ontrackend": false,
          "td_onviapad": true
        }
      ],
      "teardrop_parameters": [
        {
          "td_curve_segcount": 0,
          "td_height_ratio": 1.0,
          "td_length_ratio": 0.5,
          "td_maxheight": 2.0,
          "td_maxlen": 1.0,
          "td_target_name": "td_round_shape",
          "td_width_to_size_filter_ratio": 0.9
        },
        {
          "td_curve_segcount": 0,
          "td_height_ratio": 1.0,
          "td_length_ratio": 0.5,
          "td_maxheight": 2.0,
          "td_maxlen": 1.0,
          "td_target_name": "td_rect_shape",
          "td_width_to_size_filter_ratio": 0.9
        },
        {
          "td_curve_segcount": 0,
          "td_height_ratio": 1.0,
          "td_length_ratio": 0.5,
          "td_maxheight": 2.0,
          "td_maxlen": 1.0,
          "td_target_name": "td_track_end",
          "td_width_to_size_filter_ratio": 0.9
        }
      ],
      "track_widths": [
        0.0,
        0.127,
        0.15,
        0.18,
        0.2,
        0.254,
        0.4,
        0.5,
        0.75,
        1.0,
        1.25,
        1.5,
        1.75,
        2.0
      ],
      "via_dimensions": [
        {
          "diameter": 0.0,
          "drill": 0.0
        },
        {
          "diameter": 0.5,
          "drill": 0.15
        },
        {
          "diameter": 0.5,
          "drill": 0.15
        },
        {
          "diameter": 0.5,
          "drill": 0.15
        }
      ],
      "zones_allow_external_fillets": false,
      "zones_use_no_outline": true
    },
    "layer_presets": [],
    "viewports": []
  },
  "boards": [],
  "cvpcb": {
    "equivalence_files": []
  },
  "erc": {
    "erc_exclusions": [],
    "meta": {
      "version": 0
    },
    "pin_map": [
      [
        0,
        0,
        0,
        0,
        0,
        0,
        1,
        0,
        0,
        0,
        0,
        2
      ],
      [
        0,
        2,
        0,
        1,
        0,
        0,
        1,
        0,
        2,
        2,
        2,
        2
      ],
      [
        0,
        0,
        0,
        0,
        0,
        0,
        1,
        0,
        1,
        0,
        1,
        2
      ],
      [
        0,
        1,
        0,
        0,
        0,
        0,
        1,
        1,
        2,
        1,
        1,
        2
      ],
      [
        0,
        0,
        0,
        0,
        0,
        0,
        1,
        0,
        0,
        0,
        0,
        2
      ],
      [
        0,
        0,
        0,
        0,
        0,
        0,
        0,
        0,
        0,
        0,
        0,
        2
      ],
      [
        1,
        1,
        1,
        1,
        1,
        0,
        1,
        1,
        1,
        1,
        1,
        2
      ],
      [
        0,
        0,
        0,
        1,
        0,
        0,
        1,
        0,
        0,
        0,
        0,
        2
      ],
      [
        0,
        2,
        1,
        2,
        0,
        0,
        1,
        0,
        2,
        2,
        2,
        2
      ],
      [
        0,
        2,
        0,
        1,
        0,
        0,
        1,
        0,
        2,
        0,
        0,
        2
      ],
      [
        0,
        2,
        1,
        1,
        0,
        0,
        1,
        0,
        2,
        0,
        0,
        2
      ],
      [
        2,
        2,
        2,
        2,
        2,
        2,
        2,
        2,
        2,
        2,
        2,
        2
      ]
    ],
    "rule_severities": {
      "bus_definition_conflict": "error",
      "bus_entry_needed": "error",
      "bus_to_bus_conflict": "error",
      "bus_to_net_conflict": "error",
      "conflicting_netclasses": "error",
      "different_unit_footprint": "error",
      "different_unit_net": "error",
      "duplicate_reference": "error",
      "duplicate_sheet_names": "error",
      "endpoint_off_grid": "warning",
      "extra_units": "error",
      "global_label_dangling": "ignore",
      "hier_label_mismatch": "error",
      "label_dangling": "error",
      "lib_symbol_issues": "warning",
      "missing_bidi_pin": "warning",
      "missing_input_pin": "warning",
      "missing_power_pin": "error",
      "missing_unit": "warning",
      "multiple_net_names": "warning",
      "net_not_bus_member": "warning",
      "no_connect_connected": "warning",
      "no_connect_dangling": "warning",
      "pin_not_connected": "error",
      "pin_not_driven": "error",
      "pin_to_pin": "warning",
      "power_pin_not_driven": "error",
      "similar_labels": "warning",
      "simulation_model_issue": "ignore",
      "unannotated": "error",
      "unit_value_mismatch": "error",
      "unresolved_variable": "error",
      "wire_dangling": "error"
    }
  },
  "libraries": {
    "pinned_footprint_libs": [],
    "pinned_symbol_libs": []
  },
  "meta": {
    "filename": "scalenode-cm4-baseboard.kicad_pro",
    "version": 1
  },
  "net_settings": {
    "classes": [
      {
        "bus_width": 12,
        "clearance": 0.125,
        "diff_pair_gap": 0.25,
        "diff_pair_via_gap": 0.25,
        "diff_pair_width": 0.2,
        "line_style": 0,
        "microvia_diameter": 0.3,
        "microvia_drill": 0.1,
        "name": "Default",
        "pcb_color": "rgba(0, 0, 0, 0.000)",
        "schematic_color": "rgba(0, 0, 0, 0.000)",
        "track_width": 0.254,
        "via_diameter": 0.5,
        "via_drill": 0.15,
        "wire_width": 6
      },
      {
        "bus_width": 12,
        "clearance": 0.125,
        "diff_pair_gap": 0.2,
        "diff_pair_via_gap": 0.25,
        "diff_pair_width": 0.15,
        "line_style": 0,
        "microvia_diameter": 0.3,
        "microvia_drill": 0.1,
        "name": "Diff_100",
        "pcb_color": "rgba(0, 0, 0, 0.000)",
        "schematic_color": "rgba(0, 0, 0, 0.000)",
        "track_width": 0.15,
        "via_diameter": 0.5,
        "via_drill": 0.15,
        "wire_width": 6
      },
      {
        "bus_width": 12,
        "clearance": 0.125,
        "diff_pair_gap": 0.2,
        "diff_pair_via_gap": 0.25,
        "diff_pair_width": 0.18,
        "line_style": 0,
        "microvia_diameter": 0.3,
        "microvia_drill": 0.1,
        "name": "Diff_90",
        "pcb_color": "rgba(0, 0, 0, 0.000)",
        "schematic_color": "rgba(0, 0, 0, 0.000)",
        "track_width": 0.18,
        "via_diameter": 0.5,
        "via_drill": 0.15,
        "wire_width": 6
      },
      {
        "bus_width": 12,
        "clearance": 0.12,
        "diff_pair_gap": 0.25,
        "diff_pair_via_gap": 0.25,
        "diff_pair_width": 0.2,
        "line_style": 0,
        "microvia_diameter": 0.3,
        "microvia_drill": 0.1,
        "name": "SE_50",
        "pcb_color": "rgba(0, 0, 0, 0.000)",
        "schematic_color": "rgba(0, 0, 0, 0.000)",
        "track_width": 0.18,
        "via_diameter": 0.5,
        "via_drill": 0.15,
        "wire_width": 6
      }
    ],
    "meta": {
      "version": 3
    },
    "net_colors": null,
    "netclass_assignments": null,
    "netclass_patterns": []
  },
  "pcbnew": {
    "last_paths": {
      "gencad": "",
      "idf": "",
      "netlist": "scalenode-cm4-baseboard.net",
      "specctra_dsn": "",
      "step": "",
      "vrml": "scalenode-cm4-baseboard.wrl"
    },
    "page_layout_descr_file": ""
  },
  "schematic": {
    "annotate_start_num": 0,
    "drawing": {
      "dashed_lines_dash_length_ratio": 12.0,
      "dashed_lines_gap_length_ratio": 3.0,
      "default_line_thickness": 6.0,
      "default_text_size": 50.0,
      "field_names": [],
      "intersheets_ref_own_page": false,
      "intersheets_ref_prefix": "",
      "intersheets_ref_short": false,
      "intersheets_ref_show": false,
      "intersheets_ref_suffix": "",
      "junction_size_choice": 3,
      "label_size_ratio": 0.25,
      "pin_symbol_size": 0.0,
      "text_offset_ratio": 0.08
    },
    "legacy_lib_dir": "",
    "legacy_lib_list": [],
    "meta": {
      "version": 1
    },
    "net_format_name": "Pcbnew",
    "ngspice": {
      "fix_include_paths": true,
      "fix_passive_vals": false,
      "meta": {
        "version": 0
      },
      "model_mode": 0,
      "workbook_filename": ""
    },
    "page_layout_descr_file": "",
    "plot_directory": "doc/",
    "spice_adjust_passive_values": false,
    "spice_current_sheet_as_root": false,
    "spice_external_command": "spice \"%I\"",
    "spice_model_current_sheet_as_root": true,
    "spice_save_all_currents": false,
    "spice_save_all_voltages": false,
    "subpart_first_id": 65,
    "subpart_id_separator": 0
  },
  "sheets": [
    [
      "",
      ""
    ],
    [
      "",
      "Compute module"
    ],
    [
      "",
      "Supply"
    ],
    [
      "",
      "Interfaces"
    ],
    [
      "",
      "PoE"
    ],
    [
      "",
      "NVMe SSD"
    ],
    [
      "",
      "Expansion connectors"
    ]
  ],
  "text_variables": {}
}
